# BASEBOARD_FAB2 (Tioga Pass) — schematic netlist excerpt (pin names and nets, part order shuffled) for the footprints in the layout excerpt that follows; sources: Cadence DE-HDL packaged netlist, KiCad conversion of Wiwynn_Tioga_Pass_MB.brd

J6U2  SCONN288_H44441003  SCONN  pkg PIP  page 48
  \12v\(1)  = P12V_NVDIMM_ABC
  VSS(93)  = GND
  DQ(4)  = M_C_DQ<4>
  VSS(92)  = GND
  DQ(0)  = M_C_DQ<0>
  VSS(91)  = GND
  DQS9P  = M_C_DQS_DP<9>
  DQS9N  = M_C_DQS_DN<9>
  VSS(90)  = GND
  DQ(6)  = M_C_DQ<6>
  VSS(89)  = GND
  DQ(2)  = M_C_DQ<2>
  VSS(88)  = GND
  DQ(12)  = M_C_DQ<12>
  VSS(87)  = GND
  DQ(8)  = M_C_DQ<8>
  VSS(86)  = GND
  DQS10P  = M_C_DQS_DP<10>
  DQS10N  = M_C_DQS_DN<10>
  VSS(85)  = GND
  DQ(14)  = M_C_DQ<14>
  VSS(84)  = GND
  DQ(10)  = M_C_DQ<10>
  VSS(83)  = GND
  DQ(20)  = M_C_DQ<20>
  VSS(82)  = GND
  DQ(16)  = M_C_DQ<16>
  VSS(81)  = GND
  DQS11P  = M_C_DQS_DP<11>
  DQS11N  = M_C_DQS_DN<11>
  VSS(80)  = GND
  DQ(22)  = M_C_DQ<22>
  VSS(79)  = GND
  DQ(18)  = M_C_DQ<18>
  VSS(78)  = GND
  DQ(28)  = M_C_DQ<28>
  VSS(77)  = GND
  DQ(24)  = M_C_DQ<24>
  VSS(76)  = GND
  DQS12P  = M_C_DQS_DP<12>
  DQS12N  = M_C_DQS_DN<12>
  VSS(75)  = GND
  DQ(30)  = M_C_DQ<30>
  VSS(74)  = GND
  DQ(26)  = M_C_DQ<26>
  VSS(73)  = GND
  CB(4)  = M_C_ECC<4>
  VSS(72)  = GND
  CB(0)  = M_C_ECC<0>
  VSS(71)  = GND
  DQS17P  = M_C_DQS_DP<17>
  DQS17N  = M_C_DQS_DN<17>
  VSS(70)  = GND
  CB(6)  = M_C_ECC<6>
  VSS(69)  = GND
  CB(2)  = M_C_ECC<2>
  VSS(68)  = GND
  RESET_N  = M_ABC_RST_N
  VDD(25)  = PVDDQ_ABC
  CKE(0)  = M_C_CKE<2>
  VDD(24)  = PVDDQ_ABC
  ACT_N  = M_C_ACT_N
  BG(0)  = M_C_BG<0>
  VDD(23)  = PVDDQ_ABC
  A12  = M_C_MA<12>
  A9  = M_C_MA<9>
  VDD(22)  = PVDDQ_ABC
  A8  = M_C_MA<8>
  A6  = M_C_MA<6>
  VDD(21)  = PVDDQ_ABC
  A3  = M_C_MA<3>
  A1  = M_C_MA<1>
  VDD(20)  = PVDDQ_ABC
  CK0P  = M_C_CLK_DP<2>
  CK0N  = M_C_CLK_DN<2>
  VDD(19)  = PVDDQ_ABC
  VTT(1)  = PVTT_ABC
  EVENT_N  = FM_DIMM_EVENT_COD_N
  A0  = M_C_MA<0>
  VDD(18)  = PVDDQ_ABC
  BA(0)  = M_C_BA<0>
  A16_RAS_N  = M_C_MA<16>
  VDD(17)  = PVDDQ_ABC
  S0_N  = M_C_CS_N<4>
  VDD(16)  = PVDDQ_ABC
  A15_CAS_N  = M_C_MA<15>
  ODT(0)  = M_C_ODT<2>
  VDD(15)  = PVDDQ_ABC
  S1_N  = M_C_CS_N<5>
  VDD(14)  = PVDDQ_ABC
  ODT(1)  = M_C_ODT<3>
  VDD(13)  = PVDDQ_ABC
  S2_N_C(0)  = M_C_CS_N<6>
  VSS(67)  = GND
  DQ(36)  = M_C_DQ<36>
  VSS(66)  = GND
  DQ(32)  = M_C_DQ<32>
  VSS(65)  = GND
  DQS13P  = M_C_DQS_DP<13>
  DQS13N  = M_C_DQS_DN<13>
  VSS(64)  = GND
  DQ(38)  = M_C_DQ<38>
  VSS(63)  = GND
  DQ(34)  = M_C_DQ<34>
  VSS(62)  = GND
  DQ(44)  = M_C_DQ<44>
  VSS(61)  = GND
  DQ(40)  = M_C_DQ<40>
  VSS(60)  = GND
  DQS14P  = M_C_DQS_DP<14>
  DQS14N  = M_C_DQS_DN<14>
  VSS(59)  = GND
  DQ(46)  = M_C_DQ<46>
  VSS(58)  = GND
  DQ(42)  = M_C_DQ<42>
  VSS(57)  = GND
  DQ(52)  = M_C_DQ<52>
  VSS(56)  = GND
  DQ(48)  = M_C_DQ<48>
  VSS(55)  = GND
  DQS15P  = M_C_DQS_DP<15>
  DQS15N  = M_C_DQS_DN<15>
  VSS(54)  = GND
  DQ(54)  = M_C_DQ<54>
  VSS(53)  = GND
  DQ(50)  = M_C_DQ<50>
  VSS(52)  = GND
  DQ(60)  = M_C_DQ<60>
  VSS(51)  = GND
  DQ(56)  = M_C_DQ<56>
  VSS(50)  = GND
  DQS16P  = M_C_DQS_DP<16>
  DQS16N  = M_C_DQS_DN<16>
  VSS(49)  = GND
  DQ(62)  = M_C_DQ<62>
  VSS(48)  = GND
  DQ(58)  = M_C_DQ<58>
  VSS(47)  = GND
  SA(0)  = PVPP_ABC
  SA(1)  = GND
  SCL  = SMB_DDR_ABC_VPP_SCL
  VPP(4)  = PVPP_ABC
  VPP(3)  = PVPP_ABC
  RFU(2)  = TP_CH_C_DIMM_C1_RFU_2
  \12v\(0)  = P12V_NVDIMM_ABC
  VREFCA  = M_C_VREF
  VSS(46)  = GND
  DQ(5)  = M_C_DQ<5>
  VSS(45)  = GND
  DQ(1)  = M_C_DQ<1>
  VSS(44)  = GND
  DQS0N  = M_C_DQS_DN<0>
  DQS0P  = M_C_DQS_DP<0>
  VSS(43)  = GND
  DQ(7)  = M_C_DQ<7>
  VSS(42)  = GND
  DQ(3)  = M_C_DQ<3>
  VSS(41)  = GND
  DQ(13)  = M_C_DQ<13>
  VSS(40)  = GND
  DQ(9)  = M_C_DQ<9>
  VSS(39)  = GND
  DQS1N  = M_C_DQS_DN<1>
  DQS1P  = M_C_DQS_DP<1>
  VSS(38)  = GND
  DQ(15)  = M_C_DQ<15>
  VSS(37)  = GND
  DQ(11)  = M_C_DQ<11>
  VSS(36)  = GND
  DQ(21)  = M_C_DQ<21>
  VSS(35)  = GND
  DQ(17)  = M_C_DQ<17>
  VSS(34)  = GND
  DQS2N  = M_C_DQS_DN<2>
  DQS2P  = M_C_DQS_DP<2>
  VSS(33)  = GND
  DQ(23)  = M_C_DQ<23>
  VSS(32)  = GND
  DQ(19)  = M_C_DQ<19>
  VSS(31)  = GND
  DQ(29)  = M_C_DQ<29>
  VSS(30)  = GND
  DQ(25)  = M_C_DQ<25>
  VSS(29)  = GND
  DQS3N  = M_C_DQS_DN<3>
  DQS3P  = M_C_DQS_DP<3>
  VSS(28)  = GND
  DQ(31)  = M_C_DQ<31>
  VSS(27)  = GND
  DQ(27)  = M_C_DQ<27>
  VSS(26)  = GND
  CB(5)  = M_C_ECC<5>
  VSS(25)  = GND
  CB(1)  = M_C_ECC<1>
  VSS(24)  = GND
  DQS8N  = M_C_DQS_DN<8>
  DQS8P  = M_C_DQS_DP<8>
  VSS(23)  = GND
  CB(7)  = M_C_ECC<7>
  VSS(22)  = GND
  CB(3)  = M_C_ECC<3>
  VSS(21)  = GND
  CKE(1)  = M_C_CKE<3>
  VDD(12)  = PVDDQ_ABC
  RFU(0)  = TP_CH_C_DIMM_C1_RFU_0
  VDD(11)  = PVDDQ_ABC
  BG(1)  = M_C_BG<1>
  ALERT_N  = M_C_ALERT_N
  VDD(10)  = PVDDQ_ABC
  A11  = M_C_MA<11>
  A7  = M_C_MA<7>
  VDD(9)  = PVDDQ_ABC
  A5  = M_C_MA<5>
  A4  = M_C_MA<4>
  VDD(8)  = PVDDQ_ABC
  A2  = M_C_MA<2>
  VDD(7)  = PVDDQ_ABC
  CK1P  = M_C_CLK_DP<3>
  CK1N  = M_C_CLK_DN<3>
  VDD(6)  = PVDDQ_ABC
  VTT(0)  = PVTT_ABC
  PAR  = M_C_PAR
  VDD(5)  = PVDDQ_ABC
  BA(1)  = M_C_BA<1>
  A10  = M_C_MA<10>
  VDD(4)  = PVDDQ_ABC
  RFU(1)  = TP_CH_C_DIMM_C1_RFU_1
  A14_WE_N  = M_C_MA<14>
  VDD(3)  = PVDDQ_ABC
  SAVE_N_NC  = FM_ADR_COMPLETE_ABC_N
  VDD(2)  = PVDDQ_ABC
  A13  = M_C_MA<13>
  VDD(1)  = PVDDQ_ABC
  A17  = M_C_MA<17>
  C(2)  = M_C_C<2>
  VDD(0)  = PVDDQ_ABC
  S3_N_C(1)  = M_C_CS_N<7>
  SA(2)  = PVPP_ABC
  VSS(20)  = GND
  DQ(37)  = M_C_DQ<37>
  VSS(19)  = GND
  DQ(33)  = M_C_DQ<33>
  VSS(18)  = GND
  DQS4N  = M_C_DQS_DN<4>
  DQS4P  = M_C_DQS_DP<4>
  VSS(17)  = GND
  DQ(39)  = M_C_DQ<39>
  VSS(16)  = GND
  DQ(35)  = M_C_DQ<35>
  VSS(15)  = GND
  DQ(45)  = M_C_DQ<45>
  VSS(14)  = GND
  DQ(41)  = M_C_DQ<41>
  VSS(13)  = GND
  DQS5N  = M_C_DQS_DN<5>
  DQS5P  = M_C_DQS_DP<5>
  VSS(12)  = GND
  DQ(47)  = M_C_DQ<47>
  VSS(11)  = GND
  DQ(43)  = M_C_DQ<43>
  VSS(10)  = GND
  DQ(53)  = M_C_DQ<53>
  VSS(9)  = GND
  DQ(49)  = M_C_DQ<49>
  VSS(8)  = GND
  DQS6N  = M_C_DQS_DN<6>
  DQS6P  = M_C_DQS_DP<6>
  VSS(7)  = GND
  DQ(55)  = M_C_DQ<55>
  VSS(6)  = GND
  DQ(51)  = M_C_DQ<51>
  VSS(5)  = GND
  DQ(61)  = M_C_DQ<61>
  VSS(4)  = GND
  DQ(57)  = M_C_DQ<57>
  VSS(3)  = GND
  DQS7N  = M_C_DQS_DN<7>
  DQS7P  = M_C_DQS_DP<7>
  VSS(2)  = GND
  DQ(63)  = M_C_DQ<63>
  VSS(1)  = GND
  DQ(59)  = M_C_DQ<59>
  VSS(0)  = GND
  VDDSPD  = PVPP_ABC
  SDA  = SMB_DDR_ABC_VPP_SDA
  VPP(1)  = PVPP_ABC
  VPP(0)  = PVPP_ABC
  VPP(2)  = PVPP_ABC

(kicad_pcb
	(version 20260206)
	(generator "pcbnew")
	(generator_version "10.0")
	(general
		(thickness 1.6)
		(legacy_teardrops no)
	)
	(paper "A4")
	(title_block
		(title "Wiwynn_Tioga_Pass_MB.brd")
		(comment 1 "Tioga Pass / footprint 2838 of 4770 (J6U2), pads 152-201 of 291")
	)
	(layers
		(0 "F.Cu" signal "TOP")
		(4 "In1.Cu" signal "L2GND")
		(6 "In2.Cu" signal "L3")
		(8 "In3.Cu" signal "L4GND")
		(10 "In4.Cu" signal "L5")
		(12 "In5.Cu" signal "L6GND")
		(14 "In6.Cu" signal "L7VCC")
		(16 "In7.Cu" signal "L8VCC")
		(18 "In8.Cu" signal "L9GND")
		(20 "In9.Cu" signal "L10")
		(22 "In10.Cu" signal "L11GND")
		(24 "In11.Cu" signal "L12")
		(26 "In12.Cu" signal "L13GND")
		(2 "B.Cu" signal "BOTTOM")
		(9 "F.Adhes" user "F.Adhesive")
		(11 "B.Adhes" user "B.Adhesive")
		(13 "F.Paste" user "Package Geometry/Pastemask Top")
		(15 "B.Paste" user "Package Geometry/Pastemask Bottom")
		(5 "F.SilkS" user "Ref Des/Silkscreen Top")
		(7 "B.SilkS" user "Ref Des/Silkscreen Bottom")
		(1 "F.Mask" user "Board Geometry/Soldermask Top")
		(3 "B.Mask" user "Board Geometry/Soldermask Bottom")
		(17 "Dwgs.User" user "User.Drawings")
		(19 "Cmts.User" user "User.Comments")
		(21 "Eco1.User" user "User.Eco1")
		(23 "Eco2.User" user "User.Eco2")
		(25 "Edge.Cuts" user "Board Geometry/Outline")
		(27 "Margin" user)
		(31 "F.CrtYd" user "Package Geometry/Place Bound Top")
		(29 "B.CrtYd" user "Package Geometry/Place Bound Bottom")
		(35 "F.Fab" user "Ref Des/Assembly Top")
		(33 "B.Fab" user "Ref Des/Assembly Bottom")
	)
	(footprint ""
		(layer "B.Cu")
		(at 194.700398 -5.621782 90)
		(property "Reference" "J6U2"
			(at 2.225548 39.48811 0)
			(unlocked yes)
			(layer "B.SilkS")
			(effects
				(font
					(size 0.7874 0.5842)
					(thickness 0.1524)
				)
				(justify left mirror)
			)
		)
		(property "Value" ""
			(at 0 0 90)
			(layer "B.Fab")
			(effects
				(font
					(size 1.27 1.27)
				)
				(justify mirror)
			)
		)
		(duplicate_pad_numbers_are_jumpers no)
		(pad "149" smd rect
			(at -4.59994 3.400044 270)
			(size 1.8034 0.508)
			(layers "B.Cu" "B.Mask" "B.Paste")
			(net "GND")
		)
		(pad "150" smd rect
			(at -4.59994 4.249928 270)
			(size 1.8034 0.508)
			(layers "B.Cu" "B.Mask" "B.Paste")
			(net "M_C_DQ<1>")
		)
		(pad "151" smd rect
			(at -4.59994 5.100066 270)
			(size 1.8034 0.508)
			(layers "B.Cu" "B.Mask" "B.Paste")
			(net "GND")
		)
		(pad "152" smd rect
			(at -4.59994 5.94995 270)
			(size 1.8034 0.508)
			(layers "B.Cu" "B.Mask" "B.Paste")
			(net "M_C_DQS_DN<0>")
		)
		(pad "153" smd rect
			(at -4.59994 6.800088 270)
			(size 1.8034 0.508)
			(layers "B.Cu" "B.Mask" "B.Paste")
			(net "M_C_DQS_DP<0>")
		)
		(pad "154" smd rect
			(at -4.59994 7.649972 270)
			(size 1.8034 0.508)
			(layers "B.Cu" "B.Mask" "B.Paste")
			(net "GND")
		)
		(pad "155" smd rect
			(at -4.59994 8.50011 270)
			(size 1.8034 0.508)
			(layers "B.Cu" "B.Mask" "B.Paste")
			(net "M_C_DQ<7>")
		)
		(pad "156" smd rect
			(at -4.59994 9.349994 270)
			(size 1.8034 0.508)
			(layers "B.Cu" "B.Mask" "B.Paste")
			(net "GND")
		)
		(pad "157" smd rect
			(at -4.59994 10.199878 270)
			(size 1.8034 0.508)
			(layers "B.Cu" "B.Mask" "B.Paste")
			(net "M_C_DQ<3>")
		)
		(pad "158" smd rect
			(at -4.59994 11.050016 270)
			(size 1.8034 0.508)
			(layers "B.Cu" "B.Mask" "B.Paste")
			(net "GND")
		)
		(pad "159" smd rect
			(at -4.59994 11.8999 270)
			(size 1.8034 0.508)
			(layers "B.Cu" "B.Mask" "B.Paste")
			(net "M_C_DQ<13>")
		)
		(pad "160" smd rect
			(at -4.59994 12.750038 270)
			(size 1.8034 0.508)
			(layers "B.Cu" "B.Mask" "B.Paste")
			(net "GND")
		)
		(pad "161" smd rect
			(at -4.59994 13.599922 270)
			(size 1.8034 0.508)
			(layers "B.Cu" "B.Mask" "B.Paste")
			(net "M_C_DQ<9>")
		)
		(pad "162" smd rect
			(at -4.59994 14.45006 270)
			(size 1.8034 0.508)
			(layers "B.Cu" "B.Mask" "B.Paste")
			(net "GND")
		)
		(pad "163" smd rect
			(at -4.59994 15.299944 270)
			(size 1.8034 0.508)
			(layers "B.Cu" "B.Mask" "B.Paste")
			(net "M_C_DQS_DN<1>")
		)
		(pad "164" smd rect
			(at -4.59994 16.150082 270)
			(size 1.8034 0.508)
			(layers "B.Cu" "B.Mask" "B.Paste")
			(net "M_C_DQS_DP<1>")
		)
		(pad "165" smd rect
			(at -4.59994 16.999966 270)
			(size 1.8034 0.508)
			(layers "B.Cu" "B.Mask" "B.Paste")
			(net "GND")
		)
		(pad "166" smd rect
			(at -4.59994 17.850104 270)
			(size 1.8034 0.508)
			(layers "B.Cu" "B.Mask" "B.Paste")
			(net "M_C_DQ<15>")
		)
		(pad "167" smd rect
			(at -4.59994 18.699988 270)
			(size 1.8034 0.508)
			(layers "B.Cu" "B.Mask" "B.Paste")
			(net "GND")
		)
		(pad "168" smd rect
			(at -4.59994 19.550126 270)
			(size 1.8034 0.508)
			(layers "B.Cu" "B.Mask" "B.Paste")
			(net "M_C_DQ<11>")
		)
		(pad "169" smd rect
			(at -4.59994 20.40001 270)
			(size 1.8034 0.508)
			(layers "B.Cu" "B.Mask" "B.Paste")
			(net "GND")
		)
		(pad "170" smd rect
			(at -4.59994 21.249894 270)
			(size 1.8034 0.508)
			(layers "B.Cu" "B.Mask" "B.Paste")
			(net "M_C_DQ<21>")
		)
		(pad "171" smd rect
			(at -4.59994 22.100032 270)
			(size 1.8034 0.508)
			(layers "B.Cu" "B.Mask" "B.Paste")
			(net "GND")
		)
		(pad "172" smd rect
			(at -4.59994 22.949916 270)
			(size 1.8034 0.508)
			(layers "B.Cu" "B.Mask" "B.Paste")
			(net "M_C_DQ<17>")
		)
		(pad "173" smd rect
			(at -4.59994 23.800054 270)
			(size 1.8034 0.508)
			(layers "B.Cu" "B.Mask" "B.Paste")
			(net "GND")
		)
		(pad "174" smd rect
			(at -4.59994 24.649938 270)
			(size 1.8034 0.508)
			(layers "B.Cu" "B.Mask" "B.Paste")
			(net "M_C_DQS_DN<2>")
		)
		(pad "175" smd rect
			(at -4.59994 25.500076 270)
			(size 1.8034 0.508)
			(layers "B.Cu" "B.Mask" "B.Paste")
			(net "M_C_DQS_DP<2>")
		)
		(pad "176" smd rect
			(at -4.59994 26.34996 270)
			(size 1.8034 0.508)
			(layers "B.Cu" "B.Mask" "B.Paste")
			(net "GND")
		)
		(pad "177" smd rect
			(at -4.59994 27.200098 270)
			(size 1.8034 0.508)
			(layers "B.Cu" "B.Mask" "B.Paste")
			(net "M_C_DQ<23>")
		)
		(pad "178" smd rect
			(at -4.59994 28.049982 270)
			(size 1.8034 0.508)
			(layers "B.Cu" "B.Mask" "B.Paste")
			(net "GND")
		)
		(pad "179" smd rect
			(at -4.59994 28.90012 270)
			(size 1.8034 0.508)
			(layers "B.Cu" "B.Mask" "B.Paste")
			(net "M_C_DQ<19>")
		)
		(pad "180" smd rect
			(at -4.59994 29.750004 270)
			(size 1.8034 0.508)
			(layers "B.Cu" "B.Mask" "B.Paste")
			(net "GND")
		)
		(pad "181" smd rect
			(at -4.59994 30.599888 270)
			(size 1.8034 0.508)
			(layers "B.Cu" "B.Mask" "B.Paste")
			(net "M_C_DQ<29>")
		)
		(pad "182" smd rect
			(at -4.59994 31.450026 270)
			(size 1.8034 0.508)
			(layers "B.Cu" "B.Mask" "B.Paste")
			(net "GND")
		)
		(pad "183" smd rect
			(at -4.59994 32.29991 270)
			(size 1.8034 0.508)
			(layers "B.Cu" "B.Mask" "B.Paste")
			(net "M_C_DQ<25>")
		)
		(pad "184" smd rect
			(at -4.59994 33.150048 270)
			(size 1.8034 0.508)
			(layers "B.Cu" "B.Mask" "B.Paste")
			(net "GND")
		)
		(pad "185" smd rect
			(at -4.59994 33.999932 270)
			(size 1.8034 0.508)
			(layers "B.Cu" "B.Mask" "B.Paste")
			(net "M_C_DQS_DN<3>")
		)
		(pad "186" smd rect
			(at -4.59994 34.85007 270)
			(size 1.8034 0.508)
			(layers "B.Cu" "B.Mask" "B.Paste")
			(net "M_C_DQS_DP<3>")
		)
		(pad "187" smd rect
			(at -4.59994 35.699954 270)
			(size 1.8034 0.508)
			(layers "B.Cu" "B.Mask" "B.Paste")
			(net "GND")
		)
		(pad "188" smd rect
			(at -4.59994 36.550092 270)
			(size 1.8034 0.508)
			(layers "B.Cu" "B.Mask" "B.Paste")
			(net "M_C_DQ<31>")
		)
		(pad "189" smd rect
			(at -4.59994 37.399976 270)
			(size 1.8034 0.508)
			(layers "B.Cu" "B.Mask" "B.Paste")
			(net "GND")
		)
		(pad "190" smd rect
			(at -4.59994 38.250114 270)
			(size 1.8034 0.508)
			(layers "B.Cu" "B.Mask" "B.Paste")
			(net "M_C_DQ<27>")
		)
		(pad "191" smd rect
			(at -4.59994 39.099998 270)
			(size 1.8034 0.508)
			(layers "B.Cu" "B.Mask" "B.Paste")
			(net "GND")
		)
		(pad "192" smd rect
			(at -4.59994 39.949882 270)
			(size 1.8034 0.508)
			(layers "B.Cu" "B.Mask" "B.Paste")
			(net "M_C_ECC<5>")
		)
		(pad "193" smd rect
			(at -4.59994 40.80002 270)
			(size 1.8034 0.508)
			(layers "B.Cu" "B.Mask" "B.Paste")
			(net "GND")
		)
		(pad "194" smd rect
			(at -4.59994 41.649904 270)
			(size 1.8034 0.508)
			(layers "B.Cu" "B.Mask" "B.Paste")
			(net "M_C_ECC<1>")
		)
		(pad "195" smd rect
			(at -4.59994 42.500042 270)
			(size 1.8034 0.508)
			(layers "B.Cu" "B.Mask" "B.Paste")
			(net "GND")
		)
		(pad "196" smd rect
			(at -4.59994 43.349926 270)
			(size 1.8034 0.508)
			(layers "B.Cu" "B.Mask" "B.Paste")
			(net "M_C_DQS_DN<8>")
		)
		(pad "197" smd rect
			(at -4.59994 44.200064 270)
			(size 1.8034 0.508)
			(layers "B.Cu" "B.Mask" "B.Paste")
			(net "M_C_DQS_DP<8>")
		)
		(pad "198" smd rect
			(at -4.59994 45.049948 270)
			(size 1.8034 0.508)
			(layers "B.Cu" "B.Mask" "B.Paste")
			(net "GND")
		)
	)
)
